#ISCELL
  logical_power cad_note *
  *
#ISCELL
  pure_quanta quanta_title_block_c *
  *
#ISCELL
  standard offpage *
  page86_i1
#ISCELL
  standard offpage *
  page86_i10
#ISCELL
  standard tap *
  page86_i100
#ISCELL
  standard tap *
  page86_i101
#ISCELL
  standard tap *
  page86_i102
#ISCELL
  standard tap *
  page86_i103
#ISCELL
  standard tap *
  page86_i104
#ISCELL
  standard tap *
  page86_i105
#ISCELL
  standard tap *
  page86_i106
#ISCELL
  standard tap *
  page86_i107
#ISCELL
  standard tap *
  page86_i108
#ISCELL
  standard tap *
  page86_i109
#ISCELL
  standard offpage *
  page86_i11
#ISCELL
  standard tap *
  page86_i110
#ISCELL
  standard tap *
  page86_i111
#ISCELL
  standard tap *
  page86_i112
#ISCELL
  standard tap *
  page86_i113
#ISCELL
  standard tap *
  page86_i114
#ISCELL
  standard tap *
  page86_i115
#ISCELL
  standard tap *
  page86_i116
#ISCELL
  standard tap *
  page86_i117
#ISCELL
  standard tap *
  page86_i118
#ISCELL
  logical_power universal_gnd *
  page86_i119
#ISCELL
  logical_power vcc_core *
  page86_i12
#CELL
  pure_quanta q_cap *
  page86_i120
#CELL
  pure_quanta q_cap *
  page86_i121
#ISCELL
  logical_power universal_gnd *
  page86_i122
#CELL
  pure_quanta q_cap *
  page86_i123
#ISCELL
  logical_power vcc_core *
  page86_i124
#ISCELL
  standard offpage *
  page86_i126
#ISCELL
  standard offpage *
  page86_i127
#ISCELL
  logical_power vcc_core *
  page86_i128
#ISCELL
  standard tap *
  page86_i129
#ISCELL
  standard offpage *
  page86_i13
#ISCELL
  standard tap *
  page86_i130
#ISCELL
  standard tap *
  page86_i131
#ISCELL
  standard tap *
  page86_i132
#ISCELL
  standard tap *
  page86_i133
#ISCELL
  standard tap *
  page86_i134
#ISCELL
  standard tap *
  page86_i135
#ISCELL
  standard tap *
  page86_i136
#ISCELL
  standard tap *
  page86_i137
#ISCELL
  standard tap *
  page86_i138
#ISCELL
  standard tap *
  page86_i139
#ISCELL
  standard offpage *
  page86_i14
#ISCELL
  standard tap *
  page86_i140
#ISCELL
  standard tap *
  page86_i141
#ISCELL
  standard tap *
  page86_i142
#ISCELL
  standard tap *
  page86_i143
#ISCELL
  standard tap *
  page86_i144
#ISCELL
  standard tap *
  page86_i145
#ISCELL
  standard tap *
  page86_i146
#ISCELL
  standard tap *
  page86_i147
#ISCELL
  standard tap *
  page86_i148
#ISCELL
  standard tap *
  page86_i149
#ISCELL
  standard offpage *
  page86_i15
#ISCELL
  standard tap *
  page86_i150
#ISCELL
  standard tap *
  page86_i151
#ISCELL
  standard tap *
  page86_i152
#ISCELL
  standard tap *
  page86_i153
#ISCELL
  standard tap *
  page86_i154
#ISCELL
  standard tap *
  page86_i155
#ISCELL
  standard tap *
  page86_i156
#ISCELL
  standard tap *
  page86_i157
#ISCELL
  standard tap *
  page86_i158
#ISCELL
  standard tap *
  page86_i159
#ISCELL
  standard offpage *
  page86_i16
#ISCELL
  standard tap *
  page86_i160
#ISCELL
  standard tap *
  page86_i161
#ISCELL
  standard tap *
  page86_i162
#ISCELL
  standard tap *
  page86_i163
#ISCELL
  standard tap *
  page86_i164
#ISCELL
  standard tap *
  page86_i165
#ISCELL
  standard tap *
  page86_i166
#ISCELL
  standard tap *
  page86_i167
#ISCELL
  standard tap *
  page86_i168
#ISCELL
  standard offpage *
  page86_i169
#ISCELL
  standard offpage *
  page86_i17
#ISCELL
  standard offpage *
  page86_i170
#ISCELL
  standard offpage *
  page86_i171
#ISCELL
  standard offpage *
  page86_i172
#ISCELL
  logical_power universal_gnd *
  page86_i173
#CELL
  pure_quanta sconn288_adr50017p130cc *
  page86_i174
#ISCELL
  logical_power universal_gnd *
  page86_i175
#ISCELL
  logical_power vcc_core *
  page86_i176
#ISCELL
  standard offpage *
  page86_i177
#CELL
  pure_quanta sconn288_adr50017p130cc *
  page86_i178
#ISCELL
  standard offpage *
  page86_i179
#ISCELL
  standard offpage *
  page86_i18
#CELL
  pure_quanta q_res *
  page86_i180
#ISCELL
  standard offpage *
  page86_i19
#ISCELL
  logical_power universal_gnd *
  page86_i2
#ISCELL
  standard offpage *
  page86_i20
#ISCELL
  standard offpage *
  page86_i21
#ISCELL
  standard offpage *
  page86_i22
#ISCELL
  standard offpage *
  page86_i23
#CELL
  pure_quanta sconn288_adr50017p130cc *
  page86_i24
#ISCELL
  standard tap *
  page86_i25
#ISCELL
  standard tap *
  page86_i26
#ISCELL
  standard tap *
  page86_i27
#ISCELL
  standard tap *
  page86_i28
#ISCELL
  standard tap *
  page86_i29
#CELL
  pure_quanta q_res *
  page86_i3
#ISCELL
  standard tap *
  page86_i30
#ISCELL
  standard tap *
  page86_i31
#ISCELL
  standard tap *
  page86_i32
#ISCELL
  standard tap *
  page86_i33
#ISCELL
  standard tap *
  page86_i34
#ISCELL
  standard tap *
  page86_i35
#ISCELL
  standard tap *
  page86_i36
#ISCELL
  standard tap *
  page86_i37
#ISCELL
  standard tap *
  page86_i38
#ISCELL
  standard tap *
  page86_i39
#ISCELL
  standard offpage *
  page86_i4
#ISCELL
  standard tap *
  page86_i40
#ISCELL
  standard tap *
  page86_i41
#ISCELL
  standard tap *
  page86_i42
#ISCELL
  standard tap *
  page86_i43
#ISCELL
  standard tap *
  page86_i44
#ISCELL
  standard tap *
  page86_i45
#ISCELL
  standard tap *
  page86_i46
#ISCELL
  standard tap *
  page86_i47
#ISCELL
  standard tap *
  page86_i48
#ISCELL
  standard tap *
  page86_i49
#ISCELL
  standard offpage *
  page86_i5
#ISCELL
  standard tap *
  page86_i50
#ISCELL
  standard tap *
  page86_i51
#ISCELL
  standard tap *
  page86_i52
#ISCELL
  standard tap *
  page86_i53
#ISCELL
  standard tap *
  page86_i54
#ISCELL
  standard tap *
  page86_i55
#ISCELL
  standard tap *
  page86_i56
#ISCELL
  standard tap *
  page86_i57
#ISCELL
  standard tap *
  page86_i58
#ISCELL
  standard tap *
  page86_i59
#ISCELL
  standard tap *
  page86_i60
#ISCELL
  standard tap *
  page86_i61
#ISCELL
  standard tap *
  page86_i62
#ISCELL
  standard tap *
  page86_i63
#ISCELL
  standard tap *
  page86_i64
#ISCELL
  standard tap *
  page86_i65
#ISCELL
  standard tap *
  page86_i66
#ISCELL
  standard tap *
  page86_i67
#ISCELL
  standard tap *
  page86_i68
#ISCELL
  standard tap *
  page86_i69
#ISCELL
  standard offpage *
  page86_i7
#ISCELL
  standard tap *
  page86_i70
#ISCELL
  standard tap *
  page86_i71
#ISCELL
  standard tap *
  page86_i72
#ISCELL
  standard tap *
  page86_i73
#ISCELL
  standard tap *
  page86_i74
#ISCELL
  standard tap *
  page86_i75
#ISCELL
  standard tap *
  page86_i76
#ISCELL
  standard tap *
  page86_i77
#ISCELL
  standard tap *
  page86_i78
#ISCELL
  standard tap *
  page86_i79
#ISCELL
  standard offpage *
  page86_i8
#ISCELL
  standard tap *
  page86_i80
#ISCELL
  standard tap *
  page86_i81
#ISCELL
  standard tap *
  page86_i82
#ISCELL
  standard tap *
  page86_i83
#ISCELL
  standard tap *
  page86_i84
#ISCELL
  standard tap *
  page86_i85
#ISCELL
  standard tap *
  page86_i86
#ISCELL
  standard tap *
  page86_i87
#ISCELL
  standard tap *
  page86_i88
#ISCELL
  standard tap *
  page86_i89
#ISCELL
  standard offpage *
  page86_i9
#ISCELL
  standard tap *
  page86_i90
#ISCELL
  standard tap *
  page86_i91
#ISCELL
  standard tap *
  page86_i92
#ISCELL
  standard tap *
  page86_i93
#ISCELL
  standard tap *
  page86_i94
#ISCELL
  standard tap *
  page86_i95
#ISCELL
  standard tap *
  page86_i96
#ISCELL
  standard tap *
  page86_i97
#ISCELL
  standard tap *
  page86_i98
#ISCELL
  standard tap *
  page86_i99
